(kicad_pcb
	(version 20221018)
	(generator pcbnew)
	(general
    (thickness 1.7403)
  )
	(paper "A4")
	(title_block
    (title "Data Center RDIMM DDR4 Tester")
    (date "2024-09-30")
    (rev "1.2.4")
		(comment 9 "footprints 671-677 of 690")
	)
	(layers
    (0 "F.Cu" signal)
    (1 "In1.Cu" power)
    (2 "In2.Cu" signal)
    (3 "In3.Cu" power)
    (4 "In4.Cu" power)
    (5 "In5.Cu" signal)
    (6 "In6.Cu" power)
    (7 "In7.Cu" signal)
    (8 "In8.Cu" power)
    (9 "In9.Cu" signal)
    (10 "In10.Cu" power)
    (31 "B.Cu" signal)
    (32 "B.Adhes" user "B.Adhesive")
    (33 "F.Adhes" user "F.Adhesive")
    (34 "B.Paste" user)
    (35 "F.Paste" user)
    (36 "B.SilkS" user "B.Silkscreen")
    (37 "F.SilkS" user "F.Silkscreen")
    (38 "B.Mask" user)
    (39 "F.Mask" user)
    (40 "Dwgs.User" user "User.Drawings")
    (41 "Cmts.User" user "User.Comments")
    (42 "Eco1.User" user "User.Eco1")
    (43 "Eco2.User" user "User.Eco2")
    (44 "Edge.Cuts" user)
    (45 "Margin" user)
    (46 "B.CrtYd" user "B.Courtyard")
    (47 "F.CrtYd" user "F.Courtyard")
    (48 "B.Fab" user)
    (49 "F.Fab" user)
  )
	(footprint "data-center-rdimm-ddr4-tester-footprints:VQFN-16-1EP_3x3mm_P0.5mm_EP1.1x1.1mm" (layer "B.Cu")
    (at 119.56 88.5175 90)
    (descr "VQFN, 16 Pin (https://ww1.microchip.com/downloads/en/DeviceDoc/16L_VQFN-WFS_3x3mm_4MX_C04-00508a.pdf), generated with kicad-footprint-generator ipc_noLead_generator.py")
    (tags "VQFN NoLead")
    (property "Author" "Antmicro")
    (property "License" "Apache-2.0")
    (property "MPN" "PAC1954T-E/4MX")
    (property "Manufacturer" "Microchip Technology")
    (property "Sheetfile" "supply.kicad_sch")
    (property "Sheetname" "Supply")
    (property "ki_description" "Current/Voltage Monitor Regulator High-Side 16-VQFN (3x3)")
    (property "ki_keywords" "MONITOR, VOLTAGE")
    (attr smd)
    (fp_text reference "U19" (at 1.8475 -0.83) (layer "B.SilkS")
        (effects (font (size 0.7 0.7) (thickness 0.15)) (justify left bottom mirror))
    )
    (fp_text value "PAC1954T-E_VQFN" (at 0 -2.797 270) (layer "B.Fab") hide
        (effects (font (size 0.7 0.7) (thickness 0.15)) (justify left bottom mirror))
    )
    (fp_text user "License: Apache-2.0" (at -2.35 -7.197 270) (layer "B.Fab") hide
        (effects (font (size 0.7 0.7) (thickness 0.15)) (justify left bottom mirror))
    )
    (fp_text user "${REFERENCE}" (at -2.35 -4.797 270) (layer "B.Fab") hide
        (effects (font (size 0.7 0.7) (thickness 0.15)) (justify left bottom mirror))
    )
    (fp_text user "Author: Antmicro" (at -2.35 -5.997 270) (layer "B.Fab") hide
        (effects (font (size 0.7 0.7) (thickness 0.15)) (justify left bottom mirror))
    )
    (fp_line (start -1.611 -1.61) (end -1.611 -1.134)
      (stroke (width 0.15) (type solid)) (layer "B.SilkS"))
    (fp_line (start -1.135 -1.61) (end -1.611 -1.61)
      (stroke (width 0.15) (type solid)) (layer "B.SilkS"))
    (fp_line (start -1.135 1.611) (end -1.611 1.611)
      (stroke (width 0.15) (type solid)) (layer "B.SilkS"))
    (fp_line (start 1.134 -1.61) (end 1.61 -1.61)
      (stroke (width 0.15) (type solid)) (layer "B.SilkS"))
    (fp_line (start 1.134 1.611) (end 1.61 1.611)
      (stroke (width 0.15) (type solid)) (layer "B.SilkS"))
    (fp_line (start 1.61 -1.61) (end 1.61 -1.134)
      (stroke (width 0.15) (type solid)) (layer "B.SilkS"))
    (fp_line (start 1.61 1.611) (end 1.61 1.135)
      (stroke (width 0.15) (type solid)) (layer "B.SilkS"))
    (fp_circle (center -2.3 0.75) (end -2.25 0.75)
      (stroke (width 0.15) (type solid)) (fill solid) (layer "B.SilkS"))
    (fp_rect (start -2 2) (end 1.999 -1.999)
      (stroke (width 0.05) (type solid)) (fill none) (layer "B.CrtYd"))
    (fp_line (start -1.5 -1.499) (end -1.5 0.75)
      (stroke (width 0.15) (type solid)) (layer "B.Fab"))
    (fp_line (start -1.5 0.75) (end -0.75 1.5)
      (stroke (width 0.15) (type solid)) (layer "B.Fab"))
    (fp_line (start -0.75 1.5) (end 1.499 1.5)
      (stroke (width 0.15) (type solid)) (layer "B.Fab"))
    (fp_line (start 1.499 -1.499) (end -1.5 -1.499)
      (stroke (width 0.15) (type solid)) (layer "B.Fab"))
    (fp_line (start 1.499 1.5) (end 1.499 -1.499)
      (stroke (width 0.15) (type solid)) (layer "B.Fab"))
    (fp_circle (center -2.3 0.75) (end -2.25 0.75)
      (stroke (width 0.15) (type solid)) (fill solid) (layer "B.Fab"))
    (pad "" smd roundrect (at 0 0 90) (size 0.89 0.89) (layers "B.Paste") (roundrect_rratio 0.25))
    (pad "1" smd roundrect (at -1.464 0.75 90) (size 0.775 0.25) (layers "B.Cu" "B.Paste" "B.Mask") (roundrect_rratio 0.25)
      (net 9 "GND") (pinfunction "SLOW/~{ALERT1}") (pintype "bidirectional"))
    (pad "2" smd roundrect (at -1.464 0.25 90) (size 0.775 0.25) (layers "B.Cu" "B.Paste" "B.Mask") (roundrect_rratio 0.25)
      (net 143 "3V3_SYS") (pinfunction "VDD") (pintype "power_in"))
    (pad "3" smd roundrect (at -1.464 -0.247 90) (size 0.775 0.25) (layers "B.Cu" "B.Paste" "B.Mask") (roundrect_rratio 0.25)
      (net 9 "GND") (pinfunction "GND") (pintype "power_in"))
    (pad "4" smd roundrect (at -1.464 -0.747 90) (size 0.775 0.25) (layers "B.Cu" "B.Paste" "B.Mask") (roundrect_rratio 0.25)
      (net 358 "SCL_3V3") (pinfunction "SCL") (pintype "input"))
    (pad "5" smd roundrect (at -0.75 -1.461 90) (size 0.25 0.775) (layers "B.Cu" "B.Paste" "B.Mask") (roundrect_rratio 0.25)
      (net 357 "SDA_3V3") (pinfunction "SDA") (pintype "bidirectional"))
    (pad "6" smd roundrect (at -0.25 -1.461 90) (size 0.25 0.775) (layers "B.Cu" "B.Paste" "B.Mask") (roundrect_rratio 0.25)
      (net 143 "3V3_SYS") (pinfunction "ADDRSEL") (pintype "bidirectional"))
    (pad "7" smd roundrect (at 0.247 -1.461 90) (size 0.25 0.775) (layers "B.Cu" "B.Paste" "B.Mask") (roundrect_rratio 0.25)
      (net 837 "/Supply/VTT_SEN_-") (pinfunction "IN3-") (pintype "input"))
    (pad "8" smd roundrect (at 0.747 -1.461 90) (size 0.25 0.775) (layers "B.Cu" "B.Paste" "B.Mask") (roundrect_rratio 0.25)
      (net 834 "/Supply/VTT_SEN_+") (pinfunction "IN3+") (pintype "input"))
    (pad "9" smd roundrect (at 1.461 -0.747 90) (size 0.775 0.25) (layers "B.Cu" "B.Paste" "B.Mask") (roundrect_rratio 0.25)
      (net 806 "/Supply/VCC1V2_SEN_-") (pinfunction "IN4-") (pintype "input"))
    (pad "10" smd roundrect (at 1.461 -0.247 90) (size 0.775 0.25) (layers "B.Cu" "B.Paste" "B.Mask") (roundrect_rratio 0.25)
      (net 805 "/Supply/VCC1V2_SEN_+") (pinfunction "IN4+") (pintype "input"))
    (pad "11" smd roundrect (at 1.461 0.25 90) (size 0.775 0.25) (layers "B.Cu" "B.Paste" "B.Mask") (roundrect_rratio 0.25)
      (net 833 "/Supply/VDDQ_SEN_+") (pinfunction "IN1+") (pintype "input"))
    (pad "12" smd roundrect (at 1.461 0.75 90) (size 0.775 0.25) (layers "B.Cu" "B.Paste" "B.Mask") (roundrect_rratio 0.25)
      (net 835 "/Supply/VDDQ_SEN_-") (pinfunction "IN1-") (pintype "input"))
    (pad "13" smd roundrect (at 0.747 1.464 90) (size 0.25 0.775) (layers "B.Cu" "B.Paste" "B.Mask") (roundrect_rratio 0.25)
      (net 832 "/Supply/VPP_SEN_+") (pinfunction "IN2+") (pintype "input"))
    (pad "14" smd roundrect (at 0.247 1.464 90) (size 0.25 0.775) (layers "B.Cu" "B.Paste" "B.Mask") (roundrect_rratio 0.25)
      (net 836 "/Supply/VPP_SEN_-") (pinfunction "IN2-") (pintype "input"))
    (pad "15" smd roundrect (at -0.25 1.464 90) (size 0.25 0.775) (layers "B.Cu" "B.Paste" "B.Mask") (roundrect_rratio 0.25)
      (net 9 "GND") (pinfunction "GPIO/~{ALERT2}") (pintype "bidirectional"))
    (pad "16" smd roundrect (at -0.75 1.464 90) (size 0.25 0.775) (layers "B.Cu" "B.Paste" "B.Mask") (roundrect_rratio 0.25)
      (net 660 "Net-(U19-~{PWRDN})") (pinfunction "~{PWRDN}") (pintype "input"))
    (pad "17" smd rect (at 0 0 90) (size 1.1 1.1) (layers "B.Cu" "B.Mask")
      (net 917 "unconnected-(U19-EP-Pad17)") (pinfunction "EP") (pintype "no_connect"))
  )
	(footprint "data-center-rdimm-ddr4-tester-footprints:R_0603_1608Metric" (layer "B.Cu")
    (at 144.1 80.4)
    (descr "Resistor SMD 0603")
    (tags "resistor SMD 0603")
    (property "Author" "Antmicro")
    (property "License" "Apache-2.0")
    (property "MPN" "ERJ-UP3F3300V")
    (property "Manufacturer" "Panasonic")
    (property "Sheetfile" "supply.kicad_sch")
    (property "Sheetname" "Supply")
    (property "Tolerance" "1%")
    (property "Val" "330R")
    (property "ki_description" "330R resistor in 0603 package with 1% tolerance")
    (attr smd)
    (fp_text reference "R29" (at 1.14 -0.52 180) (layer "B.SilkS")
        (effects (font (size 0.7 0.7) (thickness 0.15)) (justify left bottom mirror))
    )
    (fp_text value "R_330R_0.25W_0603" (at 0 -1.6 180) (layer "B.Fab") hide
        (effects (font (size 0.7 0.7) (thickness 0.15)) (justify left bottom mirror))
    )
    (fp_text user "${REFERENCE}" (at -1.25 -3.898 180) (layer "B.Fab") hide
        (effects (font (size 0.7 0.7) (thickness 0.15)) (justify left bottom mirror))
    )
    (fp_text user "Author: Antmicro" (at -1.25 -4.9 180) (layer "B.Fab") hide
        (effects (font (size 0.7 0.7) (thickness 0.15)) (justify left bottom mirror))
    )
    (fp_text user "License: Apache-2.0" (at -1.25 -5.9 180) (layer "B.Fab") hide
        (effects (font (size 0.7 0.7) (thickness 0.15)) (justify left bottom mirror))
    )
    (fp_line (start -0.3 -0.3) (end 0.3 -0.3)
      (stroke (width 0.15) (type solid)) (layer "B.SilkS"))
    (fp_line (start -0.3 0.3) (end 0.3 0.3)
      (stroke (width 0.15) (type solid)) (layer "B.SilkS"))
    (fp_rect (start -1.25 0.7) (end 1.25 -0.7)
      (stroke (width 0.05) (type solid)) (fill none) (layer "B.CrtYd"))
    (fp_rect (start -0.8 0.4) (end 0.8 -0.4)
      (stroke (width 0.15) (type solid)) (fill none) (layer "B.Fab"))
    (pad "1" smd roundrect (at -0.7 0) (size 0.6 0.8) (layers "B.Cu" "B.Paste" "B.Mask") (roundrect_rratio 0.2)
      (net 855 "Net-(R29-Pad1)") (pintype "passive"))
    (pad "2" smd roundrect (at 0.7 0) (size 0.6 0.8) (layers "B.Cu" "B.Paste" "B.Mask") (roundrect_rratio 0.2)
      (net 147 "1V0_SYS") (pintype "passive"))
  )
	(footprint "data-center-rdimm-ddr4-tester-footprints:C_0201" (layer "B.Cu")
    (at 192.09 96.6)
    (descr "Capacitor SMD 0201")
    (tags "capacitor SMD 0201")
    (property "Author" "Antmicro")
    (property "Dielectric" "")
    (property "License" "Apache-2.0")
    (property "MPN" "CC0201KRX6S5BB104")
    (property "Manufacturer" "Yaego")
    (property "Sheetfile" "fpga-power.kicad_sch")
    (property "Sheetname" "FPGA power")
    (property "Val" "100n")
    (property "Voltage" "")
    (property "ki_description" " ")
    (attr smd)
    (fp_text reference "C243" (at 3.39 0.54 180) (layer "B.SilkS")
        (effects (font (size 0.7 0.7) (thickness 0.15)) (justify left bottom mirror))
    )
    (fp_text value "C_100n_0201" (at 0 -1.4 180) (layer "B.Fab") hide
        (effects (font (size 0.7 0.7) (thickness 0.15)) (justify left bottom mirror))
    )
    (fp_text user "${REFERENCE}" (at -0.72 -3.4 180) (layer "B.Fab") hide
        (effects (font (size 0.7 0.7) (thickness 0.15)) (justify left bottom mirror))
    )
    (fp_text user "License: Apache-2.0" (at -0.72 -4.4 180) (layer "B.Fab") hide
        (effects (font (size 0.7 0.7) (thickness 0.15)) (justify left bottom mirror))
    )
    (fp_text user "Author: Antmicro" (at -0.72 -5.4 180) (layer "B.Fab") hide
        (effects (font (size 0.7 0.7) (thickness 0.15)) (justify left bottom mirror))
    )
    (fp_rect (start -0.72 0.38) (end 0.72 -0.38)
      (stroke (width 0.05) (type solid)) (fill none) (layer "B.CrtYd"))
    (fp_rect (start 0.3 -0.15) (end -0.301 0.149)
      (stroke (width 0.15) (type solid)) (fill none) (layer "B.Fab"))
    (pad "" smd roundrect (at -0.349 0.002) (size 0.318 0.36) (layers "B.Paste") (roundrect_rratio 0.25))
    (pad "" smd roundrect (at 0.341 0.002) (size 0.318 0.36) (layers "B.Paste") (roundrect_rratio 0.25))
    (pad "1" smd roundrect (at -0.321 0.002) (size 0.46 0.4) (layers "B.Cu" "B.Mask") (roundrect_rratio 0.25)
      (net 147 "1V0_SYS") (pintype "passive"))
    (pad "2" smd roundrect (at 0.32 0.002) (size 0.46 0.4) (layers "B.Cu" "B.Mask") (roundrect_rratio 0.25)
      (net 9 "GND") (pintype "passive"))
  )
	(footprint "data-center-rdimm-ddr4-tester-footprints:C_0201" (layer "B.Cu")
    (at 172.65 85.05 -90)
    (descr "Capacitor SMD 0201")
    (tags "capacitor SMD 0201")
    (property "Author" "Antmicro")
    (property "Dielectric" "")
    (property "License" "Apache-2.0")
    (property "MPN" "CC0201KRX6S5BB104")
    (property "Manufacturer" "Yaego")
    (property "Sheetfile" "fpga-power.kicad_sch")
    (property "Sheetname" "FPGA power")
    (property "Val" "100n")
    (property "Voltage" "")
    (property "ki_description" " ")
    (attr smd)
    (fp_text reference "C93" (at -1.07 0.49 90) (layer "B.SilkS")
        (effects (font (size 0.7 0.7) (thickness 0.15)) (justify left bottom mirror))
    )
    (fp_text value "C_100n_0201" (at 0 -1.4 90) (layer "B.Fab") hide
        (effects (font (size 0.7 0.7) (thickness 0.15)) (justify left bottom mirror))
    )
    (fp_text user "${REFERENCE}" (at -0.72 -3.4 90) (layer "B.Fab") hide
        (effects (font (size 0.7 0.7) (thickness 0.15)) (justify left bottom mirror))
    )
    (fp_text user "Author: Antmicro" (at -0.72 -5.4 90) (layer "B.Fab") hide
        (effects (font (size 0.7 0.7) (thickness 0.15)) (justify left bottom mirror))
    )
    (fp_text user "License: Apache-2.0" (at -0.72 -4.4 90) (layer "B.Fab") hide
        (effects (font (size 0.7 0.7) (thickness 0.15)) (justify left bottom mirror))
    )
    (fp_rect (start -0.72 0.38) (end 0.72 -0.38)
      (stroke (width 0.05) (type solid)) (fill none) (layer "B.CrtYd"))
    (fp_rect (start 0.3 -0.15) (end -0.301 0.149)
      (stroke (width 0.15) (type solid)) (fill none) (layer "B.Fab"))
    (pad "" smd roundrect (at -0.349 0.002 270) (size 0.318 0.36) (layers "B.Paste") (roundrect_rratio 0.25))
    (pad "" smd roundrect (at 0.341 0.002 270) (size 0.318 0.36) (layers "B.Paste") (roundrect_rratio 0.25))
    (pad "1" smd roundrect (at -0.321 0.002 270) (size 0.46 0.4) (layers "B.Cu" "B.Mask") (roundrect_rratio 0.25)
      (net 143 "3V3_SYS") (pintype "passive"))
    (pad "2" smd roundrect (at 0.32 0.002 270) (size 0.46 0.4) (layers "B.Cu" "B.Mask") (roundrect_rratio 0.25)
      (net 9 "GND") (pintype "passive"))
  )
	(footprint "data-center-rdimm-ddr4-tester-footprints:C_0201" (layer "B.Cu")
    (at 178.16 98.07 90)
    (descr "Capacitor SMD 0201")
    (tags "capacitor SMD 0201")
    (property "Author" "Antmicro")
    (property "Dielectric" "")
    (property "License" "Apache-2.0")
    (property "MPN" "CC0201KRX6S5BB104")
    (property "Manufacturer" "Yaego")
    (property "Sheetfile" "fpga-power.kicad_sch")
    (property "Sheetname" "FPGA power")
    (property "Val" "100n")
    (property "Voltage" "")
    (property "ki_description" " ")
    (attr smd)
    (fp_text reference "C307" (at 1.18 1.2 270) (layer "B.SilkS")
        (effects (font (size 0.7 0.7) (thickness 0.15)) (justify left bottom mirror))
    )
    (fp_text value "C_100n_0201" (at 0 -1.4 270) (layer "B.Fab") hide
        (effects (font (size 0.7 0.7) (thickness 0.15)) (justify left bottom mirror))
    )
    (fp_text user "Author: Antmicro" (at -0.72 -5.4 270) (layer "B.Fab") hide
        (effects (font (size 0.7 0.7) (thickness 0.15)) (justify left bottom mirror))
    )
    (fp_text user "License: Apache-2.0" (at -0.72 -4.4 270) (layer "B.Fab") hide
        (effects (font (size 0.7 0.7) (thickness 0.15)) (justify left bottom mirror))
    )
    (fp_text user "${REFERENCE}" (at -0.72 -3.4 270) (layer "B.Fab") hide
        (effects (font (size 0.7 0.7) (thickness 0.15)) (justify left bottom mirror))
    )
    (fp_rect (start -0.72 0.38) (end 0.72 -0.38)
      (stroke (width 0.05) (type solid)) (fill none) (layer "B.CrtYd"))
    (fp_rect (start 0.3 -0.15) (end -0.301 0.149)
      (stroke (width 0.15) (type solid)) (fill none) (layer "B.Fab"))
    (pad "" smd roundrect (at -0.349 0.002 90) (size 0.318 0.36) (layers "B.Paste") (roundrect_rratio 0.25))
    (pad "" smd roundrect (at 0.341 0.002 90) (size 0.318 0.36) (layers "B.Paste") (roundrect_rratio 0.25))
    (pad "1" smd roundrect (at -0.321 0.002 90) (size 0.46 0.4) (layers "B.Cu" "B.Mask") (roundrect_rratio 0.25)
      (net 143 "3V3_SYS") (pintype "passive"))
    (pad "2" smd roundrect (at 0.32 0.002 90) (size 0.46 0.4) (layers "B.Cu" "B.Mask") (roundrect_rratio 0.25)
      (net 9 "GND") (pintype "passive"))
  )
	(footprint "data-center-rdimm-ddr4-tester-footprints:C_2220_5650Metric" (layer "B.Cu")
    (at 195.05 126)
    (descr "Capacitor SMD 2220")
    (tags "capacitor SMD 2220")
    (property "Author" "Antmicro")
    (property "Dielectric" "")
    (property "License" "Apache-2.0")
    (property "MPN" "C5750X7S2A226M280KB")
    (property "Manufacturer" "TDK")
    (property "Sheetfile" "ethernet.kicad_sch")
    (property "Sheetname" "Ethernet")
    (property "Val" "22u/100V")
    (property "Voltage" "")
    (property "ki_description" " ")
    (attr smd)
    (fp_text reference "C225" (at 4.61 -1.59 270) (layer "B.SilkS")
        (effects (font (size 0.7 0.7) (thickness 0.15)) (justify left bottom mirror))
    )
    (fp_text value "C_22u_100V_2220" (at 0 -3.9 180) (layer "B.Fab") hide
        (effects (font (size 0.7 0.7) (thickness 0.15)) (justify left bottom mirror))
    )
    (fp_text user "${REFERENCE}" (at -3.7 -5.9 180) (layer "B.Fab") hide
        (effects (font (size 0.7 0.7) (thickness 0.15)) (justify left bottom mirror))
    )
    (fp_text user "License: Apache-2.0" (at -3.7 -6.9 180) (layer "B.Fab") hide
        (effects (font (size 0.7 0.7) (thickness 0.15)) (justify left bottom mirror))
    )
    (fp_text user "Author: Antmicro" (at -3.7 -7.9 180) (layer "B.Fab") hide
        (effects (font (size 0.7 0.7) (thickness 0.15)) (justify left bottom mirror))
    )
    (fp_line (start -1.415 -2.61) (end 1.415 -2.61)
      (stroke (width 0.15) (type solid)) (layer "B.SilkS"))
    (fp_line (start -1.415 2.61) (end 1.415 2.61)
      (stroke (width 0.15) (type solid)) (layer "B.SilkS"))
    (fp_rect (start -3.7 2.95) (end 3.7 -2.95)
      (stroke (width 0.05) (type solid)) (fill none) (layer "B.CrtYd"))
    (fp_rect (start -2.85 2.5) (end 2.85 -2.5)
      (stroke (width 0.15) (type solid)) (fill none) (layer "B.Fab"))
    (pad "1" smd roundrect (at -2.55 0) (size 1.8 5.4) (layers "B.Cu" "B.Paste" "B.Mask") (roundrect_rratio 0.138889)
      (net 360 "/Ethernet/VDD") (pintype "passive"))
    (pad "2" smd roundrect (at 2.55 0) (size 1.8 5.4) (layers "B.Cu" "B.Paste" "B.Mask") (roundrect_rratio 0.138889)
      (net 604 "GNDD") (pintype "passive"))
  )
	(footprint "data-center-rdimm-ddr4-tester-footprints:C_0402_1005Metric" (layer "B.Cu")
    (at 165.4 116.3)
    (descr "Capacitor SMD 0402")
    (tags "capacitor SMD 0402")
    (property "Author" "Antmicro")
    (property "Dielectric" "")
    (property "License" "Apache-2.0")
    (property "MPN" "MC0402B104K160CT")
    (property "Manufacturer" "Multicomp")
    (property "Sheetfile" "ethernet.kicad_sch")
    (property "Sheetname" "Ethernet")
    (property "Val" "100n")
    (property "Voltage" "")
    (property "ki_description" " ")
    (attr smd)
    (fp_text reference "C312" (at 1.48 -0.53 180) (layer "B.SilkS")
        (effects (font (size 0.7 0.7) (thickness 0.15)) (justify left bottom mirror))
    )
    (fp_text value "C_100n_16V_0402" (at 0 -1.4 180) (layer "B.Fab") hide
        (effects (font (size 0.7 0.7) (thickness 0.15)) (justify left bottom mirror))
    )
    (fp_text user "Author: Antmicro" (at -0.932 -4.17 180) (layer "B.Fab") hide
        (effects (font (size 0.7 0.7) (thickness 0.15)) (justify left bottom mirror))
    )
    (fp_text user "License: Apache-2.0" (at -0.932 -5.17 180) (layer "B.Fab") hide
        (effects (font (size 0.7 0.7) (thickness 0.15)) (justify left bottom mirror))
    )
    (fp_text user "${REFERENCE}" (at -0.932 -3.168 180) (layer "B.Fab") hide
        (effects (font (size 0.7 0.7) (thickness 0.15)) (justify left bottom mirror))
    )
    (fp_rect (start -0.94 0.47) (end 0.94 -0.47)
      (stroke (width 0.05) (type solid)) (fill none) (layer "B.CrtYd"))
    (fp_rect (start -0.499 0.249) (end 0.499 -0.249)
      (stroke (width 0.15) (type solid)) (fill none) (layer "B.Fab"))
    (pad "1" smd roundrect (at -0.484 0) (size 0.59 0.64) (layers "B.Cu" "B.Paste" "B.Mask") (roundrect_rratio 0.25)
      (net 94 "Net-(J2-P5)") (pintype "passive"))
    (pad "2" smd roundrect (at 0.484 0) (size 0.59 0.64) (layers "B.Cu" "B.Paste" "B.Mask") (roundrect_rratio 0.25)
      (net 9 "GND") (pintype "passive"))
  )
)
